(kicad_pcb
	(version 20260206)
	(generator "pcbnew")
	(generator_version "10.0")
	(general
		(thickness 1.6)
		(legacy_teardrops no)
	)
	(paper "A4")
	(title_block
		(title "04192023_DAF0TMB3IC0_F0TG_MB_C_brd_V02_OCP.brd")
		(comment 1 "Grand Teton / footprints 7527-7532 of 8354")
	)
	(layers
		(0 "F.Cu" signal "TOP")
		(4 "In1.Cu" signal "GND")
		(6 "In2.Cu" signal "IN1")
		(8 "In3.Cu" signal "GND1")
		(10 "In4.Cu" signal "IN2")
		(12 "In5.Cu" signal "GND2")
		(14 "In6.Cu" signal "IN3")
		(16 "In7.Cu" signal "GND3")
		(18 "In8.Cu" signal "VCC")
		(20 "In9.Cu" signal "VCC1")
		(22 "In10.Cu" signal "GND4")
		(24 "In11.Cu" signal "IN4")
		(26 "In12.Cu" signal "GND5")
		(28 "In13.Cu" signal "IN5")
		(30 "In14.Cu" signal "GND6")
		(32 "In15.Cu" signal "IN6")
		(34 "In16.Cu" signal "GND7")
		(2 "B.Cu" signal "BOTTOM")
		(9 "F.Adhes" user "F.Adhesive")
		(11 "B.Adhes" user "B.Adhesive")
		(13 "F.Paste" user "Package Geometry/Pastemask Top")
		(15 "B.Paste" user "Package Geometry/Pastemask Bottom")
		(5 "F.SilkS" user "Ref Des/Silkscreen Top")
		(7 "B.SilkS" user "Ref Des/Silkscreen Bottom")
		(1 "F.Mask" user "Board Geometry/Soldermask Top")
		(3 "B.Mask" user "Board Geometry/Soldermask Bottom")
		(17 "Dwgs.User" user "User.Drawings")
		(19 "Cmts.User" user "User.Comments")
		(21 "Eco1.User" user "User.Eco1")
		(23 "Eco2.User" user "User.Eco2")
		(25 "Edge.Cuts" user "Board Geometry/Outline")
		(27 "Margin" user)
		(31 "F.CrtYd" user "Package Geometry/Place Bound Top")
		(29 "B.CrtYd" user "Package Geometry/Place Bound Bottom")
		(35 "F.Fab" user "Ref Des/Assembly Top")
		(33 "B.Fab" user "Ref Des/Assembly Bottom")
	)
	(footprint ""
		(layer "B.Cu")
		(at 421.486076 -362.44403)
		(property "Reference" "PR3"
			(at 0 0 0)
			(layer "B.SilkS")
			(hide yes)
			(effects
				(font
					(size 1.27 1.27)
				)
				(justify mirror)
			)
		)
		(property "Value" ""
			(at 0 0 0)
			(layer "B.Fab")
			(effects
				(font
					(size 1.27 1.27)
				)
				(justify mirror)
			)
		)
		(duplicate_pad_numbers_are_jumpers no)
		(fp_line
			(start -0.7874 -0.4064)
			(end -0.7874 0.4064)
			(stroke
				(width 0.1524)
				(type default)
			)
			(layer "B.SilkS")
		)
		(fp_line
			(start -0.7874 0.4064)
			(end 0.7874 0.4064)
			(stroke
				(width 0.1524)
				(type default)
			)
			(layer "B.SilkS")
		)
		(fp_line
			(start 0.7874 -0.4064)
			(end -0.7874 -0.4064)
			(stroke
				(width 0.1524)
				(type default)
			)
			(layer "B.SilkS")
		)
		(fp_line
			(start 0.7874 0.4064)
			(end 0.7874 -0.4064)
			(stroke
				(width 0.1524)
				(type default)
			)
			(layer "B.SilkS")
		)
		(fp_line
			(start -0.67945 -0.3048)
			(end -0.67945 0.3048)
			(stroke
				(width 0.1)
				(type default)
			)
			(layer "B.Fab")
		)
		(fp_line
			(start -0.67945 0.3048)
			(end -0.120396 0.3048)
			(stroke
				(width 0.1)
				(type default)
			)
			(layer "B.Fab")
		)
		(fp_line
			(start -0.12065 -0.3048)
			(end -0.67945 -0.3048)
			(stroke
				(width 0.1)
				(type default)
			)
			(layer "B.Fab")
		)
		(fp_line
			(start -0.12065 -0.2794)
			(end -0.12065 -0.3048)
			(stroke
				(width 0.1)
				(type default)
			)
			(layer "B.Fab")
		)
		(fp_line
			(start -0.120396 0.2794)
			(end 0.12065 0.2794)
			(stroke
				(width 0.1)
				(type default)
			)
			(layer "B.Fab")
		)
		(fp_line
			(start -0.120396 0.3048)
			(end -0.120396 0.2794)
			(stroke
				(width 0.1)
				(type default)
			)
			(layer "B.Fab")
		)
		(fp_line
			(start 0.12065 -0.305054)
			(end 0.12065 -0.2794)
			(stroke
				(width 0.1)
				(type default)
			)
			(layer "B.Fab")
		)
		(fp_line
			(start 0.12065 -0.2794)
			(end -0.12065 -0.2794)
			(stroke
				(width 0.1)
				(type default)
			)
			(layer "B.Fab")
		)
		(fp_line
			(start 0.12065 0.2794)
			(end 0.12065 0.3048)
			(stroke
				(width 0.1)
				(type default)
			)
			(layer "B.Fab")
		)
		(fp_line
			(start 0.12065 0.3048)
			(end 0.67945 0.3048)
			(stroke
				(width 0.1)
				(type default)
			)
			(layer "B.Fab")
		)
		(fp_line
			(start 0.67945 -0.305054)
			(end 0.12065 -0.305054)
			(stroke
				(width 0.1)
				(type default)
			)
			(layer "B.Fab")
		)
		(fp_line
			(start 0.67945 0.3048)
			(end 0.67945 -0.305054)
			(stroke
				(width 0.1)
				(type default)
			)
			(layer "B.Fab")
		)
		(pad "1" smd circle
			(at 0.40005 0 180)
			(size 0 0)
			(layers "B.Cu" "B.Mask" "B.Paste")
			(net "PVDD11_S3_P0_VMON")
		)
		(pad "2" smd circle
			(at -0.40005 0 180)
			(size 0 0)
			(layers "B.Cu" "B.Mask" "B.Paste")
			(net "GND")
		)
	)
	(footprint ""
		(layer "B.Cu")
		(at 404.584408 -330.849732 90)
		(property "Reference" "R451"
			(at 0 0 90)
			(layer "B.SilkS")
			(hide yes)
			(effects
				(font
					(size 1.27 1.27)
				)
				(justify mirror)
			)
		)
		(property "Value" ""
			(at 0 0 90)
			(layer "B.Fab")
			(effects
				(font
					(size 1.27 1.27)
				)
				(justify mirror)
			)
		)
		(duplicate_pad_numbers_are_jumpers no)
		(fp_line
			(start 0.7874 -0.4064)
			(end -0.7874 -0.4064)
			(stroke
				(width 0.1524)
				(type default)
			)
			(layer "B.SilkS")
		)
		(fp_line
			(start -0.7874 -0.4064)
			(end -0.7874 0.4064)
			(stroke
				(width 0.1524)
				(type default)
			)
			(layer "B.SilkS")
		)
		(fp_line
			(start 0.7874 0.4064)
			(end 0.7874 -0.4064)
			(stroke
				(width 0.1524)
				(type default)
			)
			(layer "B.SilkS")
		)
		(fp_line
			(start -0.7874 0.4064)
			(end 0.7874 0.4064)
			(stroke
				(width 0.1524)
				(type default)
			)
			(layer "B.SilkS")
		)
		(fp_line
			(start 0.67945 -0.305054)
			(end 0.12065 -0.305054)
			(stroke
				(width 0.1)
				(type default)
			)
			(layer "B.Fab")
		)
		(fp_line
			(start 0.12065 -0.305054)
			(end 0.12065 -0.2794)
			(stroke
				(width 0.1)
				(type default)
			)
			(layer "B.Fab")
		)
		(fp_line
			(start -0.12065 -0.3048)
			(end -0.67945 -0.3048)
			(stroke
				(width 0.1)
				(type default)
			)
			(layer "B.Fab")
		)
		(fp_line
			(start -0.67945 -0.3048)
			(end -0.67945 0.3048)
			(stroke
				(width 0.1)
				(type default)
			)
			(layer "B.Fab")
		)
		(fp_line
			(start 0.12065 -0.2794)
			(end -0.12065 -0.2794)
			(stroke
				(width 0.1)
				(type default)
			)
			(layer "B.Fab")
		)
		(fp_line
			(start -0.12065 -0.2794)
			(end -0.12065 -0.3048)
			(stroke
				(width 0.1)
				(type default)
			)
			(layer "B.Fab")
		)
		(fp_line
			(start 0.12065 0.2794)
			(end 0.12065 0.3048)
			(stroke
				(width 0.1)
				(type default)
			)
			(layer "B.Fab")
		)
		(fp_line
			(start -0.120396 0.2794)
			(end 0.12065 0.2794)
			(stroke
				(width 0.1)
				(type default)
			)
			(layer "B.Fab")
		)
		(fp_line
			(start 0.67945 0.3048)
			(end 0.67945 -0.305054)
			(stroke
				(width 0.1)
				(type default)
			)
			(layer "B.Fab")
		)
		(fp_line
			(start 0.12065 0.3048)
			(end 0.67945 0.3048)
			(stroke
				(width 0.1)
				(type default)
			)
			(layer "B.Fab")
		)
		(fp_line
			(start -0.120396 0.3048)
			(end -0.120396 0.2794)
			(stroke
				(width 0.1)
				(type default)
			)
			(layer "B.Fab")
		)
		(fp_line
			(start -0.67945 0.3048)
			(end -0.120396 0.3048)
			(stroke
				(width 0.1)
				(type default)
			)
			(layer "B.Fab")
		)
		(pad "1" smd circle
			(at 0.40005 0 270)
			(size 0 0)
			(layers "B.Cu" "B.Mask" "B.Paste")
			(net "CPU0_SPD_HOST_CTRL_N")
		)
		(pad "2" smd circle
			(at -0.40005 0 270)
			(size 0 0)
			(layers "B.Cu" "B.Mask" "B.Paste")
			(net "PVDD18_S5_P0")
		)
	)
	(footprint ""
		(layer "B.Cu")
		(at 109.395514 -331.404976 -90)
		(property "Reference" "PR342"
			(at 0 0 90)
			(layer "B.SilkS")
			(hide yes)
			(effects
				(font
					(size 1.27 1.27)
				)
				(justify mirror)
			)
		)
		(property "Value" ""
			(at 0 0 90)
			(layer "B.Fab")
			(effects
				(font
					(size 1.27 1.27)
				)
				(justify mirror)
			)
		)
		(duplicate_pad_numbers_are_jumpers no)
		(fp_line
			(start -0.7874 0.4064)
			(end 0.7874 0.4064)
			(stroke
				(width 0.1524)
				(type default)
			)
			(layer "B.SilkS")
		)
		(fp_line
			(start 0.7874 0.4064)
			(end 0.7874 -0.4064)
			(stroke
				(width 0.1524)
				(type default)
			)
			(layer "B.SilkS")
		)
		(fp_line
			(start -0.7874 -0.4064)
			(end -0.7874 0.4064)
			(stroke
				(width 0.1524)
				(type default)
			)
			(layer "B.SilkS")
		)
		(fp_line
			(start 0.7874 -0.4064)
			(end -0.7874 -0.4064)
			(stroke
				(width 0.1524)
				(type default)
			)
			(layer "B.SilkS")
		)
		(fp_line
			(start -0.67945 0.3048)
			(end -0.120396 0.3048)
			(stroke
				(width 0.1)
				(type default)
			)
			(layer "B.Fab")
		)
		(fp_line
			(start -0.120396 0.3048)
			(end -0.120396 0.2794)
			(stroke
				(width 0.1)
				(type default)
			)
			(layer "B.Fab")
		)
		(fp_line
			(start 0.12065 0.3048)
			(end 0.67945 0.3048)
			(stroke
				(width 0.1)
				(type default)
			)
			(layer "B.Fab")
		)
		(fp_line
			(start 0.67945 0.3048)
			(end 0.67945 -0.305054)
			(stroke
				(width 0.1)
				(type default)
			)
			(layer "B.Fab")
		)
		(fp_line
			(start -0.120396 0.2794)
			(end 0.12065 0.2794)
			(stroke
				(width 0.1)
				(type default)
			)
			(layer "B.Fab")
		)
		(fp_line
			(start 0.12065 0.2794)
			(end 0.12065 0.3048)
			(stroke
				(width 0.1)
				(type default)
			)
			(layer "B.Fab")
		)
		(fp_line
			(start -0.12065 -0.2794)
			(end -0.12065 -0.3048)
			(stroke
				(width 0.1)
				(type default)
			)
			(layer "B.Fab")
		)
		(fp_line
			(start 0.12065 -0.2794)
			(end -0.12065 -0.2794)
			(stroke
				(width 0.1)
				(type default)
			)
			(layer "B.Fab")
		)
		(fp_line
			(start -0.67945 -0.3048)
			(end -0.67945 0.3048)
			(stroke
				(width 0.1)
				(type default)
			)
			(layer "B.Fab")
		)
		(fp_line
			(start -0.12065 -0.3048)
			(end -0.67945 -0.3048)
			(stroke
				(width 0.1)
				(type default)
			)
			(layer "B.Fab")
		)
		(fp_line
			(start 0.12065 -0.305054)
			(end 0.12065 -0.2794)
			(stroke
				(width 0.1)
				(type default)
			)
			(layer "B.Fab")
		)
		(fp_line
			(start 0.67945 -0.305054)
			(end 0.12065 -0.305054)
			(stroke
				(width 0.1)
				(type default)
			)
			(layer "B.Fab")
		)
		(pad "1" smd circle
			(at 0.40005 0 90)
			(size 0 0)
			(layers "B.Cu" "B.Mask" "B.Paste")
			(net "PVDDCR_CPU1_P1")
		)
		(pad "2" smd circle
			(at -0.40005 0 90)
			(size 0 0)
			(layers "B.Cu" "B.Mask" "B.Paste")
			(net "GND")
		)
	)
	(footprint ""
		(layer "B.Cu")
		(at 202.15733 -190.94831 180)
		(property "Reference" "R314"
			(at 0 0 0)
			(layer "B.SilkS")
			(hide yes)
			(effects
				(font
					(size 1.27 1.27)
				)
				(justify mirror)
			)
		)
		(property "Value" ""
			(at 0 0 0)
			(layer "B.Fab")
			(effects
				(font
					(size 1.27 1.27)
				)
				(justify mirror)
			)
		)
		(duplicate_pad_numbers_are_jumpers no)
		(fp_line
			(start 0.7874 0.4064)
			(end 0.7874 -0.4064)
			(stroke
				(width 0.1524)
				(type default)
			)
			(layer "B.SilkS")
		)
		(fp_line
			(start 0.7874 -0.4064)
			(end -0.7874 -0.4064)
			(stroke
				(width 0.1524)
				(type default)
			)
			(layer "B.SilkS")
		)
		(fp_line
			(start -0.7874 0.4064)
			(end 0.7874 0.4064)
			(stroke
				(width 0.1524)
				(type default)
			)
			(layer "B.SilkS")
		)
		(fp_line
			(start -0.7874 -0.4064)
			(end -0.7874 0.4064)
			(stroke
				(width 0.1524)
				(type default)
			)
			(layer "B.SilkS")
		)
		(fp_line
			(start 0.67945 0.3048)
			(end 0.67945 -0.305054)
			(stroke
				(width 0.1)
				(type default)
			)
			(layer "B.Fab")
		)
		(fp_line
			(start 0.67945 -0.305054)
			(end 0.12065 -0.305054)
			(stroke
				(width 0.1)
				(type default)
			)
			(layer "B.Fab")
		)
		(fp_line
			(start 0.12065 0.3048)
			(end 0.67945 0.3048)
			(stroke
				(width 0.1)
				(type default)
			)
			(layer "B.Fab")
		)
		(fp_line
			(start 0.12065 0.2794)
			(end 0.12065 0.3048)
			(stroke
				(width 0.1)
				(type default)
			)
			(layer "B.Fab")
		)
		(fp_line
			(start 0.12065 -0.2794)
			(end -0.12065 -0.2794)
			(stroke
				(width 0.1)
				(type default)
			)
			(layer "B.Fab")
		)
		(fp_line
			(start 0.12065 -0.305054)
			(end 0.12065 -0.2794)
			(stroke
				(width 0.1)
				(type default)
			)
			(layer "B.Fab")
		)
		(fp_line
			(start -0.120396 0.3048)
			(end -0.120396 0.2794)
			(stroke
				(width 0.1)
				(type default)
			)
			(layer "B.Fab")
		)
		(fp_line
			(start -0.120396 0.2794)
			(end 0.12065 0.2794)
			(stroke
				(width 0.1)
				(type default)
			)
			(layer "B.Fab")
		)
		(fp_line
			(start -0.12065 -0.2794)
			(end -0.12065 -0.3048)
			(stroke
				(width 0.1)
				(type default)
			)
			(layer "B.Fab")
		)
		(fp_line
			(start -0.12065 -0.3048)
			(end -0.67945 -0.3048)
			(stroke
				(width 0.1)
				(type default)
			)
			(layer "B.Fab")
		)
		(fp_line
			(start -0.67945 0.3048)
			(end -0.120396 0.3048)
			(stroke
				(width 0.1)
				(type default)
			)
			(layer "B.Fab")
		)
		(fp_line
			(start -0.67945 -0.3048)
			(end -0.67945 0.3048)
			(stroke
				(width 0.1)
				(type default)
			)
			(layer "B.Fab")
		)
		(pad "1" smd circle
			(at 0.40005 0)
			(size 0 0)
			(layers "B.Cu" "B.Mask" "B.Paste")
			(net "PWRGD_CHL_CPU1_DIMM")
		)
		(pad "2" smd circle
			(at -0.40005 0)
			(size 0 0)
			(layers "B.Cu" "B.Mask" "B.Paste")
			(net "PWRGD_CHGL_CPU1")
		)
	)
	(footprint ""
		(layer "B.Cu")
		(at 97.591118 -425.19219)
		(property "Reference" "C8000"
			(at 0 0 0)
			(layer "B.SilkS")
			(hide yes)
			(effects
				(font
					(size 1.27 1.27)
				)
				(justify mirror)
			)
		)
		(property "Value" ""
			(at 0 0 0)
			(layer "B.Fab")
			(effects
				(font
					(size 1.27 1.27)
				)
				(justify mirror)
			)
		)
		(duplicate_pad_numbers_are_jumpers no)
		(fp_line
			(start -0.7874 -0.4064)
			(end -0.7874 0.4064)
			(stroke
				(width 0.1524)
				(type default)
			)
			(layer "B.SilkS")
		)
		(fp_line
			(start -0.7874 0.4064)
			(end 0.7874 0.4064)
			(stroke
				(width 0.1524)
				(type default)
			)
			(layer "B.SilkS")
		)
		(fp_line
			(start 0.7874 -0.4064)
			(end -0.7874 -0.4064)
			(stroke
				(width 0.1524)
				(type default)
			)
			(layer "B.SilkS")
		)
		(fp_line
			(start 0.7874 0.4064)
			(end 0.7874 -0.4064)
			(stroke
				(width 0.1524)
				(type default)
			)
			(layer "B.SilkS")
		)
		(fp_line
			(start -0.67945 -0.3048)
			(end -0.67945 0.3048)
			(stroke
				(width 0.1)
				(type default)
			)
			(layer "B.Fab")
		)
		(fp_line
			(start -0.67945 0.3048)
			(end -0.120396 0.3048)
			(stroke
				(width 0.1)
				(type default)
			)
			(layer "B.Fab")
		)
		(fp_line
			(start -0.12065 -0.3048)
			(end -0.67945 -0.3048)
			(stroke
				(width 0.1)
				(type default)
			)
			(layer "B.Fab")
		)
		(fp_line
			(start -0.12065 -0.2794)
			(end -0.12065 -0.3048)
			(stroke
				(width 0.1)
				(type default)
			)
			(layer "B.Fab")
		)
		(fp_line
			(start -0.120396 0.2794)
			(end 0.12065 0.2794)
			(stroke
				(width 0.1)
				(type default)
			)
			(layer "B.Fab")
		)
		(fp_line
			(start -0.120396 0.3048)
			(end -0.120396 0.2794)
			(stroke
				(width 0.1)
				(type default)
			)
			(layer "B.Fab")
		)
		(fp_line
			(start 0.12065 -0.305054)
			(end 0.12065 -0.2794)
			(stroke
				(width 0.1)
				(type default)
			)
			(layer "B.Fab")
		)
		(fp_line
			(start 0.12065 -0.2794)
			(end -0.12065 -0.2794)
			(stroke
				(width 0.1)
				(type default)
			)
			(layer "B.Fab")
		)
		(fp_line
			(start 0.12065 0.2794)
			(end 0.12065 0.3048)
			(stroke
				(width 0.1)
				(type default)
			)
			(layer "B.Fab")
		)
		(fp_line
			(start 0.12065 0.3048)
			(end 0.67945 0.3048)
			(stroke
				(width 0.1)
				(type default)
			)
			(layer "B.Fab")
		)
		(fp_line
			(start 0.67945 -0.305054)
			(end 0.12065 -0.305054)
			(stroke
				(width 0.1)
				(type default)
			)
			(layer "B.Fab")
		)
		(fp_line
			(start 0.67945 0.3048)
			(end 0.67945 -0.305054)
			(stroke
				(width 0.1)
				(type default)
			)
			(layer "B.Fab")
		)
		(pad "1" smd circle
			(at 0.40005 0 180)
			(size 0 0)
			(layers "B.Cu" "B.Mask" "B.Paste")
			(net "PRSNT_SWB_ISO_N")
		)
		(pad "2" smd circle
			(at -0.40005 0 180)
			(size 0 0)
			(layers "B.Cu" "B.Mask" "B.Paste")
			(net "GND")
		)
	)
	(footprint ""
		(layer "B.Cu")
		(at 123.357386 -267.49883)
		(property "Reference" "C2405"
			(at 0 0 0)
			(layer "B.SilkS")
			(hide yes)
			(effects
				(font
					(size 1.27 1.27)
				)
				(justify mirror)
			)
		)
		(property "Value" ""
			(at 0 0 0)
			(layer "B.Fab")
			(effects
				(font
					(size 1.27 1.27)
				)
				(justify mirror)
			)
		)
		(duplicate_pad_numbers_are_jumpers no)
		(fp_line
			(start -0.7874 -0.4064)
			(end -0.7874 0.4064)
			(stroke
				(width 0.1524)
				(type default)
			)
			(layer "B.SilkS")
		)
		(fp_line
			(start -0.7874 0.4064)
			(end 0.7874 0.4064)
			(stroke
				(width 0.1524)
				(type default)
			)
			(layer "B.SilkS")
		)
		(fp_line
			(start 0.7874 -0.4064)
			(end -0.7874 -0.4064)
			(stroke
				(width 0.1524)
				(type default)
			)
			(layer "B.SilkS")
		)
		(fp_line
			(start 0.7874 0.4064)
			(end 0.7874 -0.4064)
			(stroke
				(width 0.1524)
				(type default)
			)
			(layer "B.SilkS")
		)
		(fp_line
			(start -0.67945 -0.3048)
			(end -0.67945 0.3048)
			(stroke
				(width 0.1)
				(type default)
			)
			(layer "B.Fab")
		)
		(fp_line
			(start -0.67945 0.3048)
			(end -0.120396 0.3048)
			(stroke
				(width 0.1)
				(type default)
			)
			(layer "B.Fab")
		)
		(fp_line
			(start -0.12065 -0.3048)
			(end -0.67945 -0.3048)
			(stroke
				(width 0.1)
				(type default)
			)
			(layer "B.Fab")
		)
		(fp_line
			(start -0.12065 -0.2794)
			(end -0.12065 -0.3048)
			(stroke
				(width 0.1)
				(type default)
			)
			(layer "B.Fab")
		)
		(fp_line
			(start -0.120396 0.2794)
			(end 0.12065 0.2794)
			(stroke
				(width 0.1)
				(type default)
			)
			(layer "B.Fab")
		)
		(fp_line
			(start -0.120396 0.3048)
			(end -0.120396 0.2794)
			(stroke
				(width 0.1)
				(type default)
			)
			(layer "B.Fab")
		)
		(fp_line
			(start 0.12065 -0.305054)
			(end 0.12065 -0.2794)
			(stroke
				(width 0.1)
				(type default)
			)
			(layer "B.Fab")
		)
		(fp_line
			(start 0.12065 -0.2794)
			(end -0.12065 -0.2794)
			(stroke
				(width 0.1)
				(type default)
			)
			(layer "B.Fab")
		)
		(fp_line
			(start 0.12065 0.2794)
			(end 0.12065 0.3048)
			(stroke
				(width 0.1)
				(type default)
			)
			(layer "B.Fab")
		)
		(fp_line
			(start 0.12065 0.3048)
			(end 0.67945 0.3048)
			(stroke
				(width 0.1)
				(type default)
			)
			(layer "B.Fab")
		)
		(fp_line
			(start 0.67945 -0.305054)
			(end 0.12065 -0.305054)
			(stroke
				(width 0.1)
				(type default)
			)
			(layer "B.Fab")
		)
		(fp_line
			(start 0.67945 0.3048)
			(end 0.67945 -0.305054)
			(stroke
				(width 0.1)
				(type default)
			)
			(layer "B.Fab")
		)
		(pad "1" smd circle
			(at 0.40005 0 180)
			(size 0 0)
			(layers "B.Cu" "B.Mask" "B.Paste")
			(net "PVDDCR_CPU1_P1")
		)
		(pad "2" smd circle
			(at -0.40005 0 180)
			(size 0 0)
			(layers "B.Cu" "B.Mask" "B.Paste")
			(net "GND")
		)
	)
)
